(kicad_pcb
	(version 20260206)
	(generator "pcbnew")
	(generator_version "10.0")
	(general
		(thickness 1.6)
		(legacy_teardrops no)
	)
	(paper "A4")
	(title_block
		(title "04192023_DAF0TMB3IC0_F0TG_MB_C_brd_V02_OCP.brd")
		(comment 1 "Grand Teton / footprints 3110-3115 of 8354")
	)
	(layers
		(0 "F.Cu" signal "TOP")
		(4 "In1.Cu" signal "GND")
		(6 "In2.Cu" signal "IN1")
		(8 "In3.Cu" signal "GND1")
		(10 "In4.Cu" signal "IN2")
		(12 "In5.Cu" signal "GND2")
		(14 "In6.Cu" signal "IN3")
		(16 "In7.Cu" signal "GND3")
		(18 "In8.Cu" signal "VCC")
		(20 "In9.Cu" signal "VCC1")
		(22 "In10.Cu" signal "GND4")
		(24 "In11.Cu" signal "IN4")
		(26 "In12.Cu" signal "GND5")
		(28 "In13.Cu" signal "IN5")
		(30 "In14.Cu" signal "GND6")
		(32 "In15.Cu" signal "IN6")
		(34 "In16.Cu" signal "GND7")
		(2 "B.Cu" signal "BOTTOM")
		(9 "F.Adhes" user "F.Adhesive")
		(11 "B.Adhes" user "B.Adhesive")
		(13 "F.Paste" user "Package Geometry/Pastemask Top")
		(15 "B.Paste" user "Package Geometry/Pastemask Bottom")
		(5 "F.SilkS" user "Ref Des/Silkscreen Top")
		(7 "B.SilkS" user "Ref Des/Silkscreen Bottom")
		(1 "F.Mask" user "Board Geometry/Soldermask Top")
		(3 "B.Mask" user "Board Geometry/Soldermask Bottom")
		(17 "Dwgs.User" user "User.Drawings")
		(19 "Cmts.User" user "User.Comments")
		(21 "Eco1.User" user "User.Eco1")
		(23 "Eco2.User" user "User.Eco2")
		(25 "Edge.Cuts" user "Board Geometry/Outline")
		(27 "Margin" user)
		(31 "F.CrtYd" user "Package Geometry/Place Bound Top")
		(29 "B.CrtYd" user "Package Geometry/Place Bound Bottom")
		(35 "F.Fab" user "Ref Des/Assembly Top")
		(33 "B.Fab" user "Ref Des/Assembly Bottom")
	)
	(footprint ""
		(layer "F.Cu")
		(at 77.64399 -177.627534 90)
		(property "Reference" "PC308_C0P1_5"
			(at 0 0 90)
			(layer "F.SilkS")
			(hide yes)
			(effects
				(font
					(size 1.27 1.27)
				)
			)
		)
		(property "Value" ""
			(at 0 0 90)
			(layer "F.Fab")
			(effects
				(font
					(size 1.27 1.27)
				)
			)
		)
		(duplicate_pad_numbers_are_jumpers no)
		(fp_line
			(start 0.7874 -0.4064)
			(end 0.7874 0.4064)
			(stroke
				(width 0.1524)
				(type default)
			)
			(layer "F.SilkS")
		)
		(fp_line
			(start -0.7874 -0.4064)
			(end 0.7874 -0.4064)
			(stroke
				(width 0.1524)
				(type default)
			)
			(layer "F.SilkS")
		)
		(fp_line
			(start 0.7874 0.4064)
			(end -0.7874 0.4064)
			(stroke
				(width 0.1524)
				(type default)
			)
			(layer "F.SilkS")
		)
		(fp_line
			(start -0.7874 0.4064)
			(end -0.7874 -0.4064)
			(stroke
				(width 0.1524)
				(type default)
			)
			(layer "F.SilkS")
		)
		(fp_line
			(start -0.12065 -0.305054)
			(end -0.12065 -0.2794)
			(stroke
				(width 0.1)
				(type default)
			)
			(layer "F.Fab")
		)
		(fp_line
			(start -0.67945 -0.305054)
			(end -0.12065 -0.305054)
			(stroke
				(width 0.1)
				(type default)
			)
			(layer "F.Fab")
		)
		(fp_line
			(start 0.67945 -0.3048)
			(end 0.67945 0.3048)
			(stroke
				(width 0.1)
				(type default)
			)
			(layer "F.Fab")
		)
		(fp_line
			(start 0.12065 -0.3048)
			(end 0.67945 -0.3048)
			(stroke
				(width 0.1)
				(type default)
			)
			(layer "F.Fab")
		)
		(fp_line
			(start 0.12065 -0.2794)
			(end 0.12065 -0.3048)
			(stroke
				(width 0.1)
				(type default)
			)
			(layer "F.Fab")
		)
		(fp_line
			(start -0.12065 -0.2794)
			(end 0.12065 -0.2794)
			(stroke
				(width 0.1)
				(type default)
			)
			(layer "F.Fab")
		)
		(fp_line
			(start 0.120396 0.2794)
			(end -0.12065 0.2794)
			(stroke
				(width 0.1)
				(type default)
			)
			(layer "F.Fab")
		)
		(fp_line
			(start -0.12065 0.2794)
			(end -0.12065 0.3048)
			(stroke
				(width 0.1)
				(type default)
			)
			(layer "F.Fab")
		)
		(fp_line
			(start 0.67945 0.3048)
			(end 0.120396 0.3048)
			(stroke
				(width 0.1)
				(type default)
			)
			(layer "F.Fab")
		)
		(fp_line
			(start 0.120396 0.3048)
			(end 0.120396 0.2794)
			(stroke
				(width 0.1)
				(type default)
			)
			(layer "F.Fab")
		)
		(fp_line
			(start -0.12065 0.3048)
			(end -0.67945 0.3048)
			(stroke
				(width 0.1)
				(type default)
			)
			(layer "F.Fab")
		)
		(fp_line
			(start -0.67945 0.3048)
			(end -0.67945 -0.305054)
			(stroke
				(width 0.1)
				(type default)
			)
			(layer "F.Fab")
		)
		(pad "1" smd circle
			(at -0.40005 0 90)
			(size 0 0)
			(layers "F.Cu" "F.Mask" "F.Paste")
			(net "PVDDCR_CPU0_P1_PVCC")
		)
		(pad "2" smd circle
			(at 0.40005 0 90)
			(size 0 0)
			(layers "F.Cu" "F.Mask" "F.Paste")
			(net "GND")
		)
	)
	(footprint ""
		(layer "F.Cu")
		(at 138.092688 -386.44068 90)
		(property "Reference" "C434"
			(at 0 0 90)
			(layer "F.SilkS")
			(hide yes)
			(effects
				(font
					(size 1.27 1.27)
				)
			)
		)
		(property "Value" ""
			(at 0 0 90)
			(layer "F.Fab")
			(effects
				(font
					(size 1.27 1.27)
				)
			)
		)
		(duplicate_pad_numbers_are_jumpers no)
		(fp_line
			(start 0.7874 -0.4064)
			(end 0.7874 0.4064)
			(stroke
				(width 0.1524)
				(type default)
			)
			(layer "F.SilkS")
		)
		(fp_line
			(start -0.7874 -0.4064)
			(end 0.7874 -0.4064)
			(stroke
				(width 0.1524)
				(type default)
			)
			(layer "F.SilkS")
		)
		(fp_line
			(start 0.7874 0.4064)
			(end -0.7874 0.4064)
			(stroke
				(width 0.1524)
				(type default)
			)
			(layer "F.SilkS")
		)
		(fp_line
			(start -0.7874 0.4064)
			(end -0.7874 -0.4064)
			(stroke
				(width 0.1524)
				(type default)
			)
			(layer "F.SilkS")
		)
		(fp_line
			(start -0.12065 -0.305054)
			(end -0.12065 -0.2794)
			(stroke
				(width 0.1)
				(type default)
			)
			(layer "F.Fab")
		)
		(fp_line
			(start -0.67945 -0.305054)
			(end -0.12065 -0.305054)
			(stroke
				(width 0.1)
				(type default)
			)
			(layer "F.Fab")
		)
		(fp_line
			(start 0.67945 -0.3048)
			(end 0.67945 0.3048)
			(stroke
				(width 0.1)
				(type default)
			)
			(layer "F.Fab")
		)
		(fp_line
			(start 0.12065 -0.3048)
			(end 0.67945 -0.3048)
			(stroke
				(width 0.1)
				(type default)
			)
			(layer "F.Fab")
		)
		(fp_line
			(start 0.12065 -0.2794)
			(end 0.12065 -0.3048)
			(stroke
				(width 0.1)
				(type default)
			)
			(layer "F.Fab")
		)
		(fp_line
			(start -0.12065 -0.2794)
			(end 0.12065 -0.2794)
			(stroke
				(width 0.1)
				(type default)
			)
			(layer "F.Fab")
		)
		(fp_line
			(start 0.120396 0.2794)
			(end -0.12065 0.2794)
			(stroke
				(width 0.1)
				(type default)
			)
			(layer "F.Fab")
		)
		(fp_line
			(start -0.12065 0.2794)
			(end -0.12065 0.3048)
			(stroke
				(width 0.1)
				(type default)
			)
			(layer "F.Fab")
		)
		(fp_line
			(start 0.67945 0.3048)
			(end 0.120396 0.3048)
			(stroke
				(width 0.1)
				(type default)
			)
			(layer "F.Fab")
		)
		(fp_line
			(start 0.120396 0.3048)
			(end 0.120396 0.2794)
			(stroke
				(width 0.1)
				(type default)
			)
			(layer "F.Fab")
		)
		(fp_line
			(start -0.12065 0.3048)
			(end -0.67945 0.3048)
			(stroke
				(width 0.1)
				(type default)
			)
			(layer "F.Fab")
		)
		(fp_line
			(start -0.67945 0.3048)
			(end -0.67945 -0.305054)
			(stroke
				(width 0.1)
				(type default)
			)
			(layer "F.Fab")
		)
		(pad "1" smd circle
			(at -0.40005 0 90)
			(size 0 0)
			(layers "F.Cu" "F.Mask" "F.Paste")
			(net "P1V8_CPU1_RT_1D")
		)
		(pad "2" smd circle
			(at 0.40005 0 90)
			(size 0 0)
			(layers "F.Cu" "F.Mask" "F.Paste")
			(net "GND")
		)
	)
	(footprint ""
		(layer "F.Cu")
		(at 271.092676 -120.78335 180)
		(property "Reference" "R3703"
			(at 0 0 180)
			(layer "F.SilkS")
			(hide yes)
			(effects
				(font
					(size 1.27 1.27)
				)
			)
		)
		(property "Value" ""
			(at 0 0 180)
			(layer "F.Fab")
			(effects
				(font
					(size 1.27 1.27)
				)
			)
		)
		(duplicate_pad_numbers_are_jumpers no)
		(fp_line
			(start 0.7874 0.4064)
			(end -0.7874 0.4064)
			(stroke
				(width 0.1524)
				(type default)
			)
			(layer "F.SilkS")
		)
		(fp_line
			(start 0.7874 -0.4064)
			(end 0.7874 0.4064)
			(stroke
				(width 0.1524)
				(type default)
			)
			(layer "F.SilkS")
		)
		(fp_line
			(start -0.7874 0.4064)
			(end -0.7874 -0.4064)
			(stroke
				(width 0.1524)
				(type default)
			)
			(layer "F.SilkS")
		)
		(fp_line
			(start -0.7874 -0.4064)
			(end 0.7874 -0.4064)
			(stroke
				(width 0.1524)
				(type default)
			)
			(layer "F.SilkS")
		)
		(fp_line
			(start 0.67945 0.3048)
			(end 0.120396 0.3048)
			(stroke
				(width 0.1)
				(type default)
			)
			(layer "F.Fab")
		)
		(fp_line
			(start 0.67945 -0.3048)
			(end 0.67945 0.3048)
			(stroke
				(width 0.1)
				(type default)
			)
			(layer "F.Fab")
		)
		(fp_line
			(start 0.12065 -0.2794)
			(end 0.12065 -0.3048)
			(stroke
				(width 0.1)
				(type default)
			)
			(layer "F.Fab")
		)
		(fp_line
			(start 0.12065 -0.3048)
			(end 0.67945 -0.3048)
			(stroke
				(width 0.1)
				(type default)
			)
			(layer "F.Fab")
		)
		(fp_line
			(start 0.120396 0.3048)
			(end 0.120396 0.2794)
			(stroke
				(width 0.1)
				(type default)
			)
			(layer "F.Fab")
		)
		(fp_line
			(start 0.120396 0.2794)
			(end -0.12065 0.2794)
			(stroke
				(width 0.1)
				(type default)
			)
			(layer "F.Fab")
		)
		(fp_line
			(start -0.12065 0.3048)
			(end -0.67945 0.3048)
			(stroke
				(width 0.1)
				(type default)
			)
			(layer "F.Fab")
		)
		(fp_line
			(start -0.12065 0.2794)
			(end -0.12065 0.3048)
			(stroke
				(width 0.1)
				(type default)
			)
			(layer "F.Fab")
		)
		(fp_line
			(start -0.12065 -0.2794)
			(end 0.12065 -0.2794)
			(stroke
				(width 0.1)
				(type default)
			)
			(layer "F.Fab")
		)
		(fp_line
			(start -0.12065 -0.305054)
			(end -0.12065 -0.2794)
			(stroke
				(width 0.1)
				(type default)
			)
			(layer "F.Fab")
		)
		(fp_line
			(start -0.67945 0.3048)
			(end -0.67945 -0.305054)
			(stroke
				(width 0.1)
				(type default)
			)
			(layer "F.Fab")
		)
		(fp_line
			(start -0.67945 -0.305054)
			(end -0.12065 -0.305054)
			(stroke
				(width 0.1)
				(type default)
			)
			(layer "F.Fab")
		)
		(pad "1" smd circle
			(at -0.40005 0 180)
			(size 0 0)
			(layers "F.Cu" "F.Mask" "F.Paste")
			(net "P3V3_AUX")
		)
		(pad "2" smd circle
			(at 0.40005 0 180)
			(size 0 0)
			(layers "F.Cu" "F.Mask" "F.Paste")
			(net "PCA9548_PCIE0_ADDR2")
		)
	)
	(footprint ""
		(layer "F.Cu")
		(at 218.336368 -61.072014 180)
		(property "Reference" "PC2218"
			(at 0 0 180)
			(layer "F.SilkS")
			(hide yes)
			(effects
				(font
					(size 1.27 1.27)
				)
			)
		)
		(property "Value" ""
			(at 0 0 180)
			(layer "F.Fab")
			(effects
				(font
					(size 1.27 1.27)
				)
			)
		)
		(duplicate_pad_numbers_are_jumpers no)
		(fp_line
			(start 0.7874 0.4064)
			(end -0.7874 0.4064)
			(stroke
				(width 0.1524)
				(type default)
			)
			(layer "F.SilkS")
		)
		(fp_line
			(start 0.7874 -0.4064)
			(end 0.7874 0.4064)
			(stroke
				(width 0.1524)
				(type default)
			)
			(layer "F.SilkS")
		)
		(fp_line
			(start -0.7874 0.4064)
			(end -0.7874 -0.4064)
			(stroke
				(width 0.1524)
				(type default)
			)
			(layer "F.SilkS")
		)
		(fp_line
			(start -0.7874 -0.4064)
			(end 0.7874 -0.4064)
			(stroke
				(width 0.1524)
				(type default)
			)
			(layer "F.SilkS")
		)
		(fp_line
			(start 0.67945 0.3048)
			(end 0.120396 0.3048)
			(stroke
				(width 0.1)
				(type default)
			)
			(layer "F.Fab")
		)
		(fp_line
			(start 0.67945 -0.3048)
			(end 0.67945 0.3048)
			(stroke
				(width 0.1)
				(type default)
			)
			(layer "F.Fab")
		)
		(fp_line
			(start 0.12065 -0.2794)
			(end 0.12065 -0.3048)
			(stroke
				(width 0.1)
				(type default)
			)
			(layer "F.Fab")
		)
		(fp_line
			(start 0.12065 -0.3048)
			(end 0.67945 -0.3048)
			(stroke
				(width 0.1)
				(type default)
			)
			(layer "F.Fab")
		)
		(fp_line
			(start 0.120396 0.3048)
			(end 0.120396 0.2794)
			(stroke
				(width 0.1)
				(type default)
			)
			(layer "F.Fab")
		)
		(fp_line
			(start 0.120396 0.2794)
			(end -0.12065 0.2794)
			(stroke
				(width 0.1)
				(type default)
			)
			(layer "F.Fab")
		)
		(fp_line
			(start -0.12065 0.3048)
			(end -0.67945 0.3048)
			(stroke
				(width 0.1)
				(type default)
			)
			(layer "F.Fab")
		)
		(fp_line
			(start -0.12065 0.2794)
			(end -0.12065 0.3048)
			(stroke
				(width 0.1)
				(type default)
			)
			(layer "F.Fab")
		)
		(fp_line
			(start -0.12065 -0.2794)
			(end 0.12065 -0.2794)
			(stroke
				(width 0.1)
				(type default)
			)
			(layer "F.Fab")
		)
		(fp_line
			(start -0.12065 -0.305054)
			(end -0.12065 -0.2794)
			(stroke
				(width 0.1)
				(type default)
			)
			(layer "F.Fab")
		)
		(fp_line
			(start -0.67945 0.3048)
			(end -0.67945 -0.305054)
			(stroke
				(width 0.1)
				(type default)
			)
			(layer "F.Fab")
		)
		(fp_line
			(start -0.67945 -0.305054)
			(end -0.12065 -0.305054)
			(stroke
				(width 0.1)
				(type default)
			)
			(layer "F.Fab")
		)
		(pad "1" smd circle
			(at -0.40005 0 180)
			(size 0 0)
			(layers "F.Cu" "F.Mask" "F.Paste")
			(net "P3V3_E1S_0_R")
		)
		(pad "2" smd circle
			(at 0.40005 0 180)
			(size 0 0)
			(layers "F.Cu" "F.Mask" "F.Paste")
			(net "GND")
		)
	)
	(footprint ""
		(layer "F.Cu")
		(at 342.085676 -340.236048)
		(property "Reference" "PR93"
			(at 0 0 0)
			(layer "F.SilkS")
			(hide yes)
			(effects
				(font
					(size 1.27 1.27)
				)
			)
		)
		(property "Value" ""
			(at 0 0 0)
			(layer "F.Fab")
			(effects
				(font
					(size 1.27 1.27)
				)
			)
		)
		(duplicate_pad_numbers_are_jumpers no)
		(fp_line
			(start -0.7874 -0.4064)
			(end 0.7874 -0.4064)
			(stroke
				(width 0.1524)
				(type default)
			)
			(layer "F.SilkS")
		)
		(fp_line
			(start -0.7874 0.4064)
			(end -0.7874 -0.4064)
			(stroke
				(width 0.1524)
				(type default)
			)
			(layer "F.SilkS")
		)
		(fp_line
			(start 0.7874 -0.4064)
			(end 0.7874 0.4064)
			(stroke
				(width 0.1524)
				(type default)
			)
			(layer "F.SilkS")
		)
		(fp_line
			(start 0.7874 0.4064)
			(end -0.7874 0.4064)
			(stroke
				(width 0.1524)
				(type default)
			)
			(layer "F.SilkS")
		)
		(fp_line
			(start -0.67945 -0.305054)
			(end -0.12065 -0.305054)
			(stroke
				(width 0.1)
				(type default)
			)
			(layer "F.Fab")
		)
		(fp_line
			(start -0.67945 0.3048)
			(end -0.67945 -0.305054)
			(stroke
				(width 0.1)
				(type default)
			)
			(layer "F.Fab")
		)
		(fp_line
			(start -0.12065 -0.305054)
			(end -0.12065 -0.2794)
			(stroke
				(width 0.1)
				(type default)
			)
			(layer "F.Fab")
		)
		(fp_line
			(start -0.12065 -0.2794)
			(end 0.12065 -0.2794)
			(stroke
				(width 0.1)
				(type default)
			)
			(layer "F.Fab")
		)
		(fp_line
			(start -0.12065 0.2794)
			(end -0.12065 0.3048)
			(stroke
				(width 0.1)
				(type default)
			)
			(layer "F.Fab")
		)
		(fp_line
			(start -0.12065 0.3048)
			(end -0.67945 0.3048)
			(stroke
				(width 0.1)
				(type default)
			)
			(layer "F.Fab")
		)
		(fp_line
			(start 0.120396 0.2794)
			(end -0.12065 0.2794)
			(stroke
				(width 0.1)
				(type default)
			)
			(layer "F.Fab")
		)
		(fp_line
			(start 0.120396 0.3048)
			(end 0.120396 0.2794)
			(stroke
				(width 0.1)
				(type default)
			)
			(layer "F.Fab")
		)
		(fp_line
			(start 0.12065 -0.3048)
			(end 0.67945 -0.3048)
			(stroke
				(width 0.1)
				(type default)
			)
			(layer "F.Fab")
		)
		(fp_line
			(start 0.12065 -0.2794)
			(end 0.12065 -0.3048)
			(stroke
				(width 0.1)
				(type default)
			)
			(layer "F.Fab")
		)
		(fp_line
			(start 0.67945 -0.3048)
			(end 0.67945 0.3048)
			(stroke
				(width 0.1)
				(type default)
			)
			(layer "F.Fab")
		)
		(fp_line
			(start 0.67945 0.3048)
			(end 0.120396 0.3048)
			(stroke
				(width 0.1)
				(type default)
			)
			(layer "F.Fab")
		)
		(pad "1" smd circle
			(at -0.40005 0)
			(size 0 0)
			(layers "F.Cu" "F.Mask" "F.Paste")
			(net "PVDDCR_CPU1_P0_LSET5")
		)
		(pad "2" smd circle
			(at 0.40005 0)
			(size 0 0)
			(layers "F.Cu" "F.Mask" "F.Paste")
			(net "GND")
		)
	)
	(footprint ""
		(layer "F.Cu")
		(at 153.88463 -95.612458)
		(property "Reference" "U244"
			(at 0.0762 1.95961 0)
			(unlocked yes)
			(layer "F.SilkS")
			(effects
				(font
					(size 0.7874 0.5842)
					(thickness 0.1524)
				)
			)
		)
		(property "Value" ""
			(at 0 0 0)
			(layer "F.Fab")
			(effects
				(font
					(size 1.27 1.27)
				)
			)
		)
		(duplicate_pad_numbers_are_jumpers no)
		(fp_line
			(start -1.7272 1.1176)
			(end -1.7272 -1.1176)
			(stroke
				(width 0.1524)
				(type default)
			)
			(layer "F.SilkS")
		)
		(fp_line
			(start -0.254 -1.1176)
			(end -1.7272 -1.1176)
			(stroke
				(width 0.1524)
				(type default)
			)
			(layer "F.SilkS")
		)
		(fp_line
			(start 0 -0.7366)
			(end -0.254 -1.1176)
			(stroke
				(width 0.1524)
				(type default)
			)
			(layer "F.SilkS")
		)
		(fp_line
			(start 0.254 -1.1176)
			(end 0 -0.7366)
			(stroke
				(width 0.1524)
				(type default)
			)
			(layer "F.SilkS")
		)
		(fp_line
			(start 1.7272 -1.1176)
			(end 0.254 -1.1176)
			(stroke
				(width 0.1524)
				(type default)
			)
			(layer "F.SilkS")
		)
		(fp_line
			(start 1.7272 -1.1176)
			(end 1.7272 1.1176)
			(stroke
				(width 0.1524)
				(type default)
			)
			(layer "F.SilkS")
		)
		(fp_line
			(start 1.7272 1.1176)
			(end -1.7272 1.1176)
			(stroke
				(width 0.1524)
				(type default)
			)
			(layer "F.SilkS")
		)
		(fp_poly
			(pts
				(xy -2.7178 -1.030986) (xy -1.9558 -0.649986) (xy -2.7178 -0.268986)
			)
			(stroke
				(width 0)
				(type default)
			)
			(fill yes)
			(layer "F.SilkS")
		)
		(fp_line
			(start -1.5748 -1.1176)
			(end -1.5748 1.1176)
			(stroke
				(width 0.1)
				(type default)
			)
			(layer "F.Fab")
		)
		(fp_line
			(start -1.5748 1.1176)
			(end 1.5748 1.1176)
			(stroke
				(width 0.1)
				(type default)
			)
			(layer "F.Fab")
		)
		(fp_line
			(start 1.5748 -1.1176)
			(end -1.5748 -1.1176)
			(stroke
				(width 0.1)
				(type default)
			)
			(layer "F.Fab")
		)
		(fp_line
			(start 1.5748 1.1176)
			(end 1.5748 -1.1176)
			(stroke
				(width 0.1)
				(type default)
			)
			(layer "F.Fab")
		)
		(fp_poly
			(pts
				(xy -1.9558 -0.649986) (xy -2.7178 -0.268986) (xy -2.7178 -1.030986)
			)
			(stroke
				(width 0)
				(type default)
			)
			(fill yes)
			(layer "F.Fab")
		)
		(pad "1" smd rect
			(at -0.999998 -0.649986 270)
			(size 0.3556 1.1176)
			(layers "F.Cu" "F.Mask" "F.Paste")
			(net "OCP_SFF_NOT_PRSNT_RBT_ARB_IN")
		)
		(pad "2" smd rect
			(at -0.999998 0 270)
			(size 0.3556 1.1176)
			(layers "F.Cu" "F.Mask" "F.Paste")
			(net "GND")
		)
		(pad "3" smd rect
			(at -0.999998 0.649986 270)
			(size 0.3556 1.1176)
			(layers "F.Cu" "F.Mask" "F.Paste")
			(net "OCP_SFF_RBT_ARB_IN")
		)
		(pad "4" smd rect
			(at 0.999998 0.649986 270)
			(size 0.3556 1.1176)
			(layers "F.Cu" "F.Mask" "F.Paste")
			(net "OCP_SFF_RBT_ARB_IN_MUX1_R")
		)
		(pad "5" smd rect
			(at 0.999998 0 270)
			(size 0.3556 1.1176)
			(layers "F.Cu" "F.Mask" "F.Paste")
			(net "P3V3_AUX")
		)
		(pad "6" smd rect
			(at 0.999998 -0.649986 270)
			(size 0.3556 1.1176)
			(layers "F.Cu" "F.Mask" "F.Paste")
			(net "OCP_SFF_PRSNT_ALL_R3_N")
		)
	)
)
